# T6G (Grand Teton) — schematic netlist excerpt (pin names and nets, part order shuffled) for the footprints in the layout excerpt that follows; sources: Cadence DE-HDL packaged netlist, KiCad conversion of 04192023_DAF0TMB3IC0_F0TG_MB_C_brd_V02_OCP.brd

C6012  Q_CAP  0.1UF 25V 10% X7R  pkg 0402  page 112 : A = BUF2_VDD ; B = GND
R9008  Q_RES  4.7K 5% CHIP  pkg 0402LF  page 123 : A = P3V3_AUX ; B = PRSNT_CABLE_SWB_B2

(kicad_pcb
	(version 20260206)
	(generator "pcbnew")
	(generator_version "10.0")
	(general
		(thickness 1.6)
		(legacy_teardrops no)
	)
	(paper "A4")
	(title_block
		(title "04192023_DAF0TMB3IC0_F0TG_MB_C_brd_V02_OCP.brd")
		(comment 1 "Grand Teton / footprints 4586-4587 of 8354")
	)
	(layers
		(0 "F.Cu" signal "TOP")
		(4 "In1.Cu" signal "GND")
		(6 "In2.Cu" signal "IN1")
		(8 "In3.Cu" signal "GND1")
		(10 "In4.Cu" signal "IN2")
		(12 "In5.Cu" signal "GND2")
		(14 "In6.Cu" signal "IN3")
		(16 "In7.Cu" signal "GND3")
		(18 "In8.Cu" signal "VCC")
		(20 "In9.Cu" signal "VCC1")
		(22 "In10.Cu" signal "GND4")
		(24 "In11.Cu" signal "IN4")
		(26 "In12.Cu" signal "GND5")
		(28 "In13.Cu" signal "IN5")
		(30 "In14.Cu" signal "GND6")
		(32 "In15.Cu" signal "IN6")
		(34 "In16.Cu" signal "GND7")
		(2 "B.Cu" signal "BOTTOM")
		(9 "F.Adhes" user "F.Adhesive")
		(11 "B.Adhes" user "B.Adhesive")
		(13 "F.Paste" user "Package Geometry/Pastemask Top")
		(15 "B.Paste" user "Package Geometry/Pastemask Bottom")
		(5 "F.SilkS" user "Ref Des/Silkscreen Top")
		(7 "B.SilkS" user "Ref Des/Silkscreen Bottom")
		(1 "F.Mask" user "Board Geometry/Soldermask Top")
		(3 "B.Mask" user "Board Geometry/Soldermask Bottom")
		(17 "Dwgs.User" user "User.Drawings")
		(19 "Cmts.User" user "User.Comments")
		(21 "Eco1.User" user "User.Eco1")
		(23 "Eco2.User" user "User.Eco2")
		(25 "Edge.Cuts" user "Board Geometry/Outline")
		(27 "Margin" user)
		(31 "F.CrtYd" user "Package Geometry/Place Bound Top")
		(29 "B.CrtYd" user "Package Geometry/Place Bound Bottom")
		(35 "F.Fab" user "Ref Des/Assembly Top")
		(33 "B.Fab" user "Ref Des/Assembly Bottom")
	)
	(footprint ""
		(layer "F.Cu")
		(at 21.712682 -422.437052)
		(property "Reference" "C6012"
			(at 0 0 0)
			(layer "F.SilkS")
			(hide yes)
			(effects
				(font
					(size 1.27 1.27)
				)
			)
		)
		(property "Value" ""
			(at 0 0 0)
			(layer "F.Fab")
			(effects
				(font
					(size 1.27 1.27)
				)
			)
		)
		(duplicate_pad_numbers_are_jumpers no)
		(fp_line
			(start -0.7874 -0.4064)
			(end 0.7874 -0.4064)
			(stroke
				(width 0.1524)
				(type default)
			)
			(layer "F.SilkS")
		)
		(fp_line
			(start -0.7874 0.4064)
			(end -0.7874 -0.4064)
			(stroke
				(width 0.1524)
				(type default)
			)
			(layer "F.SilkS")
		)
		(fp_line
			(start 0.7874 -0.4064)
			(end 0.7874 0.4064)
			(stroke
				(width 0.1524)
				(type default)
			)
			(layer "F.SilkS")
		)
		(fp_line
			(start 0.7874 0.4064)
			(end -0.7874 0.4064)
			(stroke
				(width 0.1524)
				(type default)
			)
			(layer "F.SilkS")
		)
		(fp_line
			(start -0.67945 -0.305054)
			(end -0.12065 -0.305054)
			(stroke
				(width 0.1)
				(type default)
			)
			(layer "F.Fab")
		)
		(fp_line
			(start -0.67945 0.3048)
			(end -0.67945 -0.305054)
			(stroke
				(width 0.1)
				(type default)
			)
			(layer "F.Fab")
		)
		(fp_line
			(start -0.12065 -0.305054)
			(end -0.12065 -0.2794)
			(stroke
				(width 0.1)
				(type default)
			)
			(layer "F.Fab")
		)
		(fp_line
			(start -0.12065 -0.2794)
			(end 0.12065 -0.2794)
			(stroke
				(width 0.1)
				(type default)
			)
			(layer "F.Fab")
		)
		(fp_line
			(start -0.12065 0.2794)
			(end -0.12065 0.3048)
			(stroke
				(width 0.1)
				(type default)
			)
			(layer "F.Fab")
		)
		(fp_line
			(start -0.12065 0.3048)
			(end -0.67945 0.3048)
			(stroke
				(width 0.1)
				(type default)
			)
			(layer "F.Fab")
		)
		(fp_line
			(start 0.120396 0.2794)
			(end -0.12065 0.2794)
			(stroke
				(width 0.1)
				(type default)
			)
			(layer "F.Fab")
		)
		(fp_line
			(start 0.120396 0.3048)
			(end 0.120396 0.2794)
			(stroke
				(width 0.1)
				(type default)
			)
			(layer "F.Fab")
		)
		(fp_line
			(start 0.12065 -0.3048)
			(end 0.67945 -0.3048)
			(stroke
				(width 0.1)
				(type default)
			)
			(layer "F.Fab")
		)
		(fp_line
			(start 0.12065 -0.2794)
			(end 0.12065 -0.3048)
			(stroke
				(width 0.1)
				(type default)
			)
			(layer "F.Fab")
		)
		(fp_line
			(start 0.67945 -0.3048)
			(end 0.67945 0.3048)
			(stroke
				(width 0.1)
				(type default)
			)
			(layer "F.Fab")
		)
		(fp_line
			(start 0.67945 0.3048)
			(end 0.120396 0.3048)
			(stroke
				(width 0.1)
				(type default)
			)
			(layer "F.Fab")
		)
		(pad "1" smd circle
			(at -0.40005 0)
			(size 0 0)
			(layers "F.Cu" "F.Mask" "F.Paste")
			(net "BUF2_VDD")
		)
		(pad "2" smd circle
			(at 0.40005 0)
			(size 0 0)
			(layers "F.Cu" "F.Mask" "F.Paste")
			(net "GND")
		)
	)
	(footprint ""
		(layer "F.Cu")
		(at 179.244752 -418.831268 -90)
		(property "Reference" "R9008"
			(at 0 0 270)
			(layer "F.SilkS")
			(hide yes)
			(effects
				(font
					(size 1.27 1.27)
				)
			)
		)
		(property "Value" ""
			(at 0 0 270)
			(layer "F.Fab")
			(effects
				(font
					(size 1.27 1.27)
				)
			)
		)
		(duplicate_pad_numbers_are_jumpers no)
		(fp_line
			(start -0.7874 0.4064)
			(end -0.7874 -0.4064)
			(stroke
				(width 0.1524)
				(type default)
			)
			(layer "F.SilkS")
		)
		(fp_line
			(start 0.7874 0.4064)
			(end -0.7874 0.4064)
			(stroke
				(width 0.1524)
				(type default)
			)
			(layer "F.SilkS")
		)
		(fp_line
			(start -0.7874 -0.4064)
			(end 0.7874 -0.4064)
			(stroke
				(width 0.1524)
				(type default)
			)
			(layer "F.SilkS")
		)
		(fp_line
			(start 0.7874 -0.4064)
			(end 0.7874 0.4064)
			(stroke
				(width 0.1524)
				(type default)
			)
			(layer "F.SilkS")
		)
		(fp_line
			(start -0.67945 0.3048)
			(end -0.67945 -0.305054)
			(stroke
				(width 0.1)
				(type default)
			)
			(layer "F.Fab")
		)
		(fp_line
			(start -0.12065 0.3048)
			(end -0.67945 0.3048)
			(stroke
				(width 0.1)
				(type default)
			)
			(layer "F.Fab")
		)
		(fp_line
			(start 0.120396 0.3048)
			(end 0.120396 0.2794)
			(stroke
				(width 0.1)
				(type default)
			)
			(layer "F.Fab")
		)
		(fp_line
			(start 0.67945 0.3048)
			(end 0.120396 0.3048)
			(stroke
				(width 0.1)
				(type default)
			)
			(layer "F.Fab")
		)
		(fp_line
			(start -0.12065 0.2794)
			(end -0.12065 0.3048)
			(stroke
				(width 0.1)
				(type default)
			)
			(layer "F.Fab")
		)
		(fp_line
			(start 0.120396 0.2794)
			(end -0.12065 0.2794)
			(stroke
				(width 0.1)
				(type default)
			)
			(layer "F.Fab")
		)
		(fp_line
			(start -0.12065 -0.2794)
			(end 0.12065 -0.2794)
			(stroke
				(width 0.1)
				(type default)
			)
			(layer "F.Fab")
		)
		(fp_line
			(start 0.12065 -0.2794)
			(end 0.12065 -0.3048)
			(stroke
				(width 0.1)
				(type default)
			)
			(layer "F.Fab")
		)
		(fp_line
			(start 0.12065 -0.3048)
			(end 0.67945 -0.3048)
			(stroke
				(width 0.1)
				(type default)
			)
			(layer "F.Fab")
		)
		(fp_line
			(start 0.67945 -0.3048)
			(end 0.67945 0.3048)
			(stroke
				(width 0.1)
				(type default)
			)
			(layer "F.Fab")
		)
		(fp_line
			(start -0.67945 -0.305054)
			(end -0.12065 -0.305054)
			(stroke
				(width 0.1)
				(type default)
			)
			(layer "F.Fab")
		)
		(fp_line
			(start -0.12065 -0.305054)
			(end -0.12065 -0.2794)
			(stroke
				(width 0.1)
				(type default)
			)
			(layer "F.Fab")
		)
		(pad "1" smd circle
			(at -0.40005 0 270)
			(size 0 0)
			(layers "F.Cu" "F.Mask" "F.Paste")
			(net "P3V3_AUX")
		)
		(pad "2" smd circle
			(at 0.40005 0 270)
			(size 0 0)
			(layers "F.Cu" "F.Mask" "F.Paste")
			(net "PRSNT_CABLE_SWB_B2")
		)
	)
)
